FILE_TYPE = MACRO_DRAWING;
SET COLOR_WIRE YELLOW;
SET COLOR_PROP ORANGE;
SET COLOR_DOT WHITE;
SET COLOR_ARC YELLOW;
SET COLOR_BODY GREEN;
SET COLOR_NOTE PURPLE;
SET PROP_DISPLAY VALUE;
SET PAGE_NUMBER P43;
FORCEADD OFFPAGE..1
(-875 550);
FORCEPROP 2 LAST $XR0 215 
J 0
(-1157 550);
DISPLAY 0.638298 (-1157 550);
PAINT MONO (-1157 550);
FORCEPROP 2 LAST CDS_LIB standard
J 0
(-875 550);
PAINT MONO (-875 550);
DISPLAY INVISIBLE (-875 550);
FORCEPROP 1 LAST OFFPAGE TRUE
J 0
(-550 425);
DISPLAY 0.872340 (-550 425);
DISPLAY INVISIBLE (-550 425);
FORCEPROP 1 LAST COMMENT_BODY TRUE
J 0
(-750 450);
DISPLAY 0.872340 (-750 450);
PAINT GREEN (-750 450);
DISPLAY INVISIBLE (-750 450);
FORCEPROP 2 LAST PATH I1
J 0
(-825 625);
DISPLAY 1.021277 (-825 625);
DISPLAY INVISIBLE (-825 625);
FORCEADD OFFPAGE..2
(2125 800);
FORCEPROP 2 LAST $XR1 43 
J 0
(2404 800);
DISPLAY 0.638298 (2404 800);
PAINT MONO (2404 800);
FORCEPROP 2 LAST $XR0 15 
J 0
(2314 800);
DISPLAY 0.638298 (2314 800);
PAINT MONO (2314 800);
FORCEPROP 2 LAST CDS_LIB standard
J 0
(2125 800);
PAINT MONO (2125 800);
DISPLAY INVISIBLE (2125 800);
FORCEPROP 1 LAST OFFPAGE TRUE
J 0
(2450 675);
DISPLAY 1.170213 (2450 675);
PAINT GREEN (2450 675);
DISPLAY INVISIBLE (2450 675);
FORCEPROP 1 LAST COMMENT_BODY TRUE
J 0
(2080 705);
DISPLAY 1.170213 (2080 705);
PAINT GREEN (2080 705);
DISPLAY INVISIBLE (2080 705);
FORCEPROP 2 LAST PATH I10
J 0
(2300 875);
DISPLAY 1.021277 (2300 875);
DISPLAY INVISIBLE (2300 875);
FORCEADD OFFPAGE..2
(2125 550);
FORCEPROP 2 LAST $XR1 46 
J 0
(2404 550);
DISPLAY 0.638298 (2404 550);
PAINT MONO (2404 550);
FORCEPROP 2 LAST $XR0 43 
J 0
(2314 550);
DISPLAY 0.638298 (2314 550);
PAINT MONO (2314 550);
FORCEPROP 2 LAST CDS_LIB standard
J 0
(2125 550);
PAINT MONO (2125 550);
DISPLAY INVISIBLE (2125 550);
FORCEPROP 1 LAST OFFPAGE TRUE
J 0
(2450 425);
DISPLAY 1.170213 (2450 425);
PAINT GREEN (2450 425);
DISPLAY INVISIBLE (2450 425);
FORCEPROP 1 LAST COMMENT_BODY TRUE
J 0
(2080 455);
DISPLAY 1.170213 (2080 455);
PAINT GREEN (2080 455);
DISPLAY INVISIBLE (2080 455);
FORCEPROP 2 LAST PATH I11
J 0
(2300 625);
DISPLAY 1.021277 (2300 625);
DISPLAY INVISIBLE (2300 625);
FORCEADD Q_RES..1
(425 800);
FORCEPROP 1 LAST PART_NUMBER CS03322FB03
J 0
(300 900);
DISPLAY 0.787234 (300 900);
DISPLAY INVISIBLE (300 900);
FORCEPROP 1 LAST PACK_TYPE 0402LF
J 0
(725 975);
DISPLAY 0.787234 (725 975);
FORCEPROP 1 LAST VALUE 33.2
J 2
(725 800);
DISPLAY 0.787234 (725 800);
FORCEPROP 1 LAST TOLERANCE 1%
J 0
(750 800);
DISPLAY 0.787234 (750 800);
FORCEPROP 1 LAST WATTAGE 1/16W
J 2
(675 975);
DISPLAY 0.787234 (675 975);
FORCEPROP 1 LAST MATERIAL CHIP
J 0
(300 975);
DISPLAY 0.787234 (300 975);
FORCEPROP 1 LAST $LOCATION R67
J 0
(200 800);
DISPLAY 0.787234 (200 800);
FORCEPROP 1 LASTPIN (325 800) $PN 1
J 0
(337 812);
DISPLAY 0.787234 (337 812);
FORCEPROP 1 LASTPIN (525 800) $PN 2
J 0
(487 812);
DISPLAY 0.787234 (487 812);
FORCEPROP 2 LAST CDS_LIB pure_quanta
J 0
(425 800);
PAINT MONO (425 800);
DISPLAY INVISIBLE (425 800);
FORCEPROP 2 LAST CDS_LOCATION R67
J 0
(675 1025);
DISPLAY 1.021277 (675 1025);
DISPLAY INVISIBLE (675 1025);
FORCEPROP 2 LAST $SEC 1
J 0
(675 1025);
DISPLAY 0.680851 (675 1025);
PAINT MONO (675 1025);
DISPLAY INVISIBLE (675 1025);
FORCEPROP 2 LAST CDS_SEC 1
J 0
(675 1025);
DISPLAY 1.021277 (675 1025);
DISPLAY INVISIBLE (675 1025);
FORCEPROP 1 LAST PATH I12
J 0
(375 950);
DISPLAY 0.978723 (375 950);
PAINT WHITE (375 950);
DISPLAY INVISIBLE (375 950);
FORCEADD Q_RES..1
(425 550);
FORCEPROP 1 LAST PART_NUMBER CS03322FB03
J 0
(300 650);
DISPLAY 0.787234 (300 650);
DISPLAY INVISIBLE (300 650);
FORCEPROP 1 LAST PACK_TYPE 0402LF
J 0
(725 725);
DISPLAY 0.787234 (725 725);
FORCEPROP 1 LAST WATTAGE 1/16W
J 2
(675 725);
DISPLAY 0.787234 (675 725);
FORCEPROP 1 LAST MATERIAL CHIP
J 0
(300 725);
DISPLAY 0.787234 (300 725);
FORCEPROP 1 LAST TOLERANCE 1%
J 0
(750 550);
DISPLAY 0.787234 (750 550);
FORCEPROP 1 LAST VALUE 33.2
J 2
(725 550);
DISPLAY 0.787234 (725 550);
FORCEPROP 1 LAST $LOCATION R68
J 0
(200 550);
DISPLAY 0.787234 (200 550);
FORCEPROP 1 LASTPIN (325 550) $PN 1
J 0
(337 562);
DISPLAY 0.787234 (337 562);
FORCEPROP 1 LASTPIN (525 550) $PN 2
J 0
(487 562);
DISPLAY 0.787234 (487 562);
FORCEPROP 2 LAST CDS_LIB pure_quanta
J 0
(425 550);
PAINT MONO (425 550);
DISPLAY INVISIBLE (425 550);
FORCEPROP 2 LAST CDS_LOCATION R68
J 0
(675 775);
DISPLAY 1.021277 (675 775);
DISPLAY INVISIBLE (675 775);
FORCEPROP 2 LAST $SEC 1
J 0
(675 775);
DISPLAY 0.680851 (675 775);
PAINT MONO (675 775);
DISPLAY INVISIBLE (675 775);
FORCEPROP 2 LAST CDS_SEC 1
J 0
(675 775);
DISPLAY 1.021277 (675 775);
DISPLAY INVISIBLE (675 775);
FORCEPROP 1 LAST PATH I13
J 0
(375 700);
DISPLAY 0.978723 (375 700);
PAINT WHITE (375 700);
DISPLAY INVISIBLE (375 700);
FORCEADD OFFPAGE..1
(-875 -1875);
FORCEPROP 2 LAST $XR1 15 
J 0
(-1216 -1875);
DISPLAY 0.638298 (-1216 -1875);
PAINT MONO (-1216 -1875);
FORCEPROP 2 LAST $XR0 43 
J 0
(-1126 -1875);
DISPLAY 0.638298 (-1126 -1875);
PAINT MONO (-1126 -1875);
FORCEPROP 2 LAST CDS_LIB standard
J 0
(-875 -1875);
PAINT MONO (-875 -1875);
DISPLAY INVISIBLE (-875 -1875);
FORCEPROP 1 LAST OFFPAGE TRUE
J 0
(-550 -2000);
DISPLAY 0.872340 (-550 -2000);
DISPLAY INVISIBLE (-550 -2000);
FORCEPROP 1 LAST COMMENT_BODY TRUE
J 0
(-750 -1975);
DISPLAY 0.872340 (-750 -1975);
PAINT GREEN (-750 -1975);
DISPLAY INVISIBLE (-750 -1975);
FORCEPROP 2 LAST PATH I14
J 0
(-825 -1800);
DISPLAY 1.021277 (-825 -1800);
DISPLAY INVISIBLE (-825 -1800);
FORCEADD OFFPAGE..1
(-875 -2125);
FORCEPROP 2 LAST $XR1 46 
J 0
(-1216 -2125);
DISPLAY 0.638298 (-1216 -2125);
PAINT MONO (-1216 -2125);
FORCEPROP 2 LAST $XR0 43 
J 0
(-1126 -2125);
DISPLAY 0.638298 (-1126 -2125);
PAINT MONO (-1126 -2125);
FORCEPROP 2 LAST CDS_LIB standard
J 0
(-875 -2125);
PAINT MONO (-875 -2125);
DISPLAY INVISIBLE (-875 -2125);
FORCEPROP 1 LAST OFFPAGE TRUE
J 0
(-550 -2250);
DISPLAY 0.872340 (-550 -2250);
DISPLAY INVISIBLE (-550 -2250);
FORCEPROP 1 LAST COMMENT_BODY TRUE
J 0
(-750 -2225);
DISPLAY 0.872340 (-750 -2225);
PAINT GREEN (-750 -2225);
DISPLAY INVISIBLE (-750 -2225);
FORCEPROP 2 LAST PATH I15
J 0
(-825 -2050);
DISPLAY 1.021277 (-825 -2050);
DISPLAY INVISIBLE (-825 -2050);
FORCEADD Q_RES..1
(475 -1875);
FORCEPROP 1 LAST PART_NUMBER CS31002FB08
J 0
(375 -1800);
DISPLAY 0.787234 (375 -1800);
DISPLAY INVISIBLE (375 -1800);
FORCEPROP 1 LAST TOLERANCE 1%
J 0
(800 -1875);
DISPLAY 0.787234 (800 -1875);
FORCEPROP 1 LAST VALUE 10K
J 2
(775 -1875);
DISPLAY 0.787234 (775 -1875);
FORCEPROP 1 LAST WATTAGE 1/16W
J 2
(775 -1725);
DISPLAY 0.787234 (775 -1725);
FORCEPROP 1 LAST MATERIAL CHIP
J 0
(375 -1725);
DISPLAY 0.787234 (375 -1725);
FORCEPROP 1 LAST PACK_TYPE 0402LF
J 0
(925 -1875);
DISPLAY 0.787234 (925 -1875);
FORCEPROP 1 LAST $LOCATION R69
J 0
(225 -1875);
DISPLAY 0.978723 (225 -1875);
FORCEPROP 1 LASTPIN (375 -1875) $PN 1
J 0
(387 -1863);
DISPLAY 0.787234 (387 -1863);
FORCEPROP 1 LASTPIN (575 -1875) $PN 2
J 0
(537 -1863);
DISPLAY 0.787234 (537 -1863);
FORCEPROP 2 LAST CDS_LIB pure_quanta
J 0
(475 -1875);
PAINT MONO (475 -1875);
DISPLAY INVISIBLE (475 -1875);
FORCEPROP 2 LAST CDS_LOCATION R69
J 0
(775 -1675);
DISPLAY 1.021277 (775 -1675);
DISPLAY INVISIBLE (775 -1675);
FORCEPROP 2 LAST $SEC 1
J 0
(775 -1675);
DISPLAY 0.680851 (775 -1675);
PAINT MONO (775 -1675);
DISPLAY INVISIBLE (775 -1675);
FORCEPROP 2 LAST CDS_SEC 1
J 0
(775 -1675);
DISPLAY 1.021277 (775 -1675);
DISPLAY INVISIBLE (775 -1675);
FORCEPROP 1 LAST PATH I16
J 0
(425 -1725);
DISPLAY 0.978723 (425 -1725);
PAINT WHITE (425 -1725);
DISPLAY INVISIBLE (425 -1725);
FORCEADD Q_RES..1
(475 -2125);
FORCEPROP 1 LAST PART_NUMBER CS31002FB08
J 0
(375 -2050);
DISPLAY 0.787234 (375 -2050);
DISPLAY INVISIBLE (375 -2050);
FORCEPROP 1 LAST TOLERANCE 1%
J 0
(800 -2125);
DISPLAY 0.787234 (800 -2125);
FORCEPROP 1 LAST MATERIAL CHIP
J 0
(375 -1975);
DISPLAY 0.787234 (375 -1975);
FORCEPROP 1 LAST WATTAGE 1/16W
J 2
(775 -1975);
DISPLAY 0.787234 (775 -1975);
FORCEPROP 1 LAST VALUE 10K
J 2
(775 -2125);
DISPLAY 0.787234 (775 -2125);
FORCEPROP 1 LAST PACK_TYPE 0402LF
J 0
(925 -2125);
DISPLAY 0.787234 (925 -2125);
FORCEPROP 1 LAST $LOCATION R70
J 0
(225 -2125);
DISPLAY 0.978723 (225 -2125);
FORCEPROP 1 LASTPIN (375 -2125) $PN 1
J 0
(387 -2113);
DISPLAY 0.787234 (387 -2113);
FORCEPROP 1 LASTPIN (575 -2125) $PN 2
J 0
(537 -2113);
DISPLAY 0.787234 (537 -2113);
FORCEPROP 2 LAST CDS_LIB pure_quanta
J 0
(475 -2125);
PAINT MONO (475 -2125);
DISPLAY INVISIBLE (475 -2125);
FORCEPROP 2 LAST CDS_LOCATION R70
J 0
(775 -1925);
DISPLAY 1.021277 (775 -1925);
DISPLAY INVISIBLE (775 -1925);
FORCEPROP 2 LAST $SEC 1
J 0
(775 -1925);
DISPLAY 0.680851 (775 -1925);
PAINT MONO (775 -1925);
DISPLAY INVISIBLE (775 -1925);
FORCEPROP 2 LAST CDS_SEC 1
J 0
(775 -1925);
DISPLAY 1.021277 (775 -1925);
DISPLAY INVISIBLE (775 -1925);
FORCEPROP 1 LAST PATH I17
J 0
(425 -1975);
DISPLAY 0.978723 (425 -1975);
PAINT WHITE (425 -1975);
DISPLAY INVISIBLE (425 -1975);
FORCEADD OFFPAGE..1
(-875 800);
FORCEPROP 2 LAST $XR0 215 
J 0
(-1157 800);
DISPLAY 0.638298 (-1157 800);
PAINT MONO (-1157 800);
FORCEPROP 2 LAST CDS_LIB standard
J 0
(-875 800);
PAINT MONO (-875 800);
DISPLAY INVISIBLE (-875 800);
FORCEPROP 1 LAST OFFPAGE TRUE
J 0
(-550 675);
DISPLAY 0.872340 (-550 675);
DISPLAY INVISIBLE (-550 675);
FORCEPROP 1 LAST COMMENT_BODY TRUE
J 0
(-750 700);
DISPLAY 0.872340 (-750 700);
PAINT GREEN (-750 700);
DISPLAY INVISIBLE (-750 700);
FORCEPROP 2 LAST PATH I2
J 0
(-825 875);
DISPLAY 1.021277 (-825 875);
DISPLAY INVISIBLE (-825 875);
FORCEADD UNIVERSAL_GND..1
(1275 -2600);
FORCEPROP 3 LASTPIN (1275 -2550) SIG_NAME GND\g
J 0
(1285 -2540);
DISPLAY 0.659574 (1285 -2540);
PAINT MONO (1285 -2540);
DISPLAY INVISIBLE (1285 -2540);
FORCEPROP 2 LAST CDS_LIB logical_power
J 0
(1275 -2600);
PAINT MONO (1275 -2600);
DISPLAY INVISIBLE (1275 -2600);
FORCEPROP 1 LAST HDL_POWER GND
J 1
(1300 -2675);
DISPLAY 0.872340 (1300 -2675);
PAINT GREEN (1300 -2675);
DISPLAY INVISIBLE (1300 -2675);
FORCEPROP 1 LAST PATH I20
J 0
(1350 -2600);
DISPLAY 0.872340 (1350 -2600);
PAINT AQUA (1350 -2600);
DISPLAY INVISIBLE (1350 -2600);
FORCEADD OFFPAGE..1
(3575 50);
FORCEPROP 2 LAST $XR0 15 
J 0
(3354 50);
DISPLAY 0.638298 (3354 50);
PAINT MONO (3354 50);
FORCEPROP 2 LAST CDS_LIB standard
J 0
(3575 50);
PAINT MONO (3575 50);
DISPLAY INVISIBLE (3575 50);
FORCEPROP 1 LAST OFFPAGE TRUE
J 0
(3900 -75);
DISPLAY 0.872340 (3900 -75);
DISPLAY INVISIBLE (3900 -75);
FORCEPROP 1 LAST COMMENT_BODY TRUE
J 0
(3700 -50);
DISPLAY 0.872340 (3700 -50);
PAINT GREEN (3700 -50);
DISPLAY INVISIBLE (3700 -50);
FORCEPROP 2 LAST PATH I47
J 0
(3300 100);
DISPLAY 1.021277 (3300 100);
DISPLAY INVISIBLE (3300 100);
FORCEADD Q_RES..1
(4875 50);
FORCEPROP 1 LAST PART_NUMBER CS31002FB08
J 0
(4725 150);
DISPLAY 0.787234 (4725 150);
DISPLAY INVISIBLE (4725 150);
FORCEPROP 1 LAST VALUE 10K
J 2
(5125 50);
DISPLAY 0.787234 (5125 50);
FORCEPROP 1 LAST WATTAGE 1/16W
J 2
(5125 200);
DISPLAY 0.787234 (5125 200);
FORCEPROP 1 LAST MATERIAL CHIP
J 0
(4725 200);
DISPLAY 0.787234 (4725 200);
FORCEPROP 1 LAST TOLERANCE 1%
J 0
(5175 50);
DISPLAY 0.787234 (5175 50);
FORCEPROP 1 LAST PACK_TYPE 0402LF
J 0
(5175 200);
DISPLAY 0.787234 (5175 200);
FORCEPROP 1 LAST $LOCATION R1226
J 0
(4600 50);
DISPLAY 0.787234 (4600 50);
FORCEPROP 1 LASTPIN (4775 50) $PN 1
J 0
(4787 62);
DISPLAY 0.787234 (4787 62);
FORCEPROP 1 LASTPIN (4975 50) $PN 2
J 0
(4937 62);
DISPLAY 0.787234 (4937 62);
FORCEPROP 2 LAST CDS_LIB pure_quanta
J 0
(4875 50);
PAINT MONO (4875 50);
DISPLAY INVISIBLE (4875 50);
FORCEPROP 2 LAST CDS_LOCATION R1226
J 0
(5175 250);
DISPLAY 1.021277 (5175 250);
DISPLAY INVISIBLE (5175 250);
FORCEPROP 2 LAST $SEC 1
J 0
(5175 250);
DISPLAY 0.680851 (5175 250);
PAINT MONO (5175 250);
DISPLAY INVISIBLE (5175 250);
FORCEPROP 2 LAST CDS_SEC 1
J 0
(5175 250);
DISPLAY 1.021277 (5175 250);
DISPLAY INVISIBLE (5175 250);
FORCEPROP 1 LAST PATH I52
J 0
(4825 200);
DISPLAY 0.978723 (4825 200);
PAINT WHITE (4825 200);
DISPLAY INVISIBLE (4825 200);
FORCEADD UNIVERSAL_GND..1
(5700 -375);
FORCEPROP 3 LASTPIN (5700 -325) SIG_NAME GND\g
J 0
(5710 -315);
DISPLAY 0.659574 (5710 -315);
PAINT MONO (5710 -315);
DISPLAY INVISIBLE (5710 -315);
FORCEPROP 2 LAST CDS_LIB logical_power
J 0
(5700 -375);
PAINT MONO (5700 -375);
DISPLAY INVISIBLE (5700 -375);
FORCEPROP 1 LAST HDL_POWER GND
J 1
(5725 -450);
DISPLAY 0.872340 (5725 -450);
PAINT GREEN (5725 -450);
DISPLAY INVISIBLE (5725 -450);
FORCEPROP 1 LAST PATH I54
J 0
(5775 -375);
DISPLAY 0.872340 (5775 -375);
PAINT AQUA (5775 -375);
DISPLAY INVISIBLE (5775 -375);
FORCEADD OFFPAGE..1
(3575 -200);
FORCEPROP 2 LAST $XR0 46 
J 0
(3354 -200);
DISPLAY 0.638298 (3354 -200);
PAINT MONO (3354 -200);
FORCEPROP 2 LAST CDS_LIB standard
J 0
(3575 -200);
PAINT MONO (3575 -200);
DISPLAY INVISIBLE (3575 -200);
FORCEPROP 1 LAST OFFPAGE TRUE
J 0
(3900 -325);
DISPLAY 0.872340 (3900 -325);
DISPLAY INVISIBLE (3900 -325);
FORCEPROP 1 LAST COMMENT_BODY TRUE
J 0
(3700 -300);
DISPLAY 0.872340 (3700 -300);
PAINT GREEN (3700 -300);
DISPLAY INVISIBLE (3700 -300);
FORCEPROP 2 LAST PATH I55
J 0
(3300 -150);
DISPLAY 1.021277 (3300 -150);
DISPLAY INVISIBLE (3300 -150);
FORCEADD Q_RES..1
(4875 -200);
FORCEPROP 1 LAST PART_NUMBER CS31002FB08
J 0
(4725 -100);
DISPLAY 0.808511 (4725 -100);
DISPLAY INVISIBLE (4725 -100);
FORCEPROP 1 LAST TOLERANCE 1%
J 0
(5175 -200);
DISPLAY 0.808511 (5175 -200);
FORCEPROP 1 LAST PACK_TYPE 0402LF
J 0
(5175 -25);
DISPLAY 0.808511 (5175 -25);
FORCEPROP 1 LAST WATTAGE 1/16W
J 2
(5125 -25);
DISPLAY 0.808511 (5125 -25);
FORCEPROP 1 LAST MATERIAL CHIP
J 0
(4725 -25);
DISPLAY 0.808511 (4725 -25);
FORCEPROP 1 LAST VALUE 10K
J 2
(5125 -200);
DISPLAY 0.808511 (5125 -200);
FORCEPROP 1 LAST $LOCATION R1227
J 0
(4600 -200);
DISPLAY 0.787234 (4600 -200);
FORCEPROP 1 LASTPIN (4775 -200) $PN 1
J 0
(4787 -188);
DISPLAY 0.787234 (4787 -188);
FORCEPROP 1 LASTPIN (4975 -200) $PN 2
J 0
(4937 -188);
DISPLAY 0.787234 (4937 -188);
FORCEPROP 2 LAST CDS_LIB pure_quanta
J 0
(4875 -200);
PAINT MONO (4875 -200);
DISPLAY INVISIBLE (4875 -200);
FORCEPROP 2 LAST CDS_LOCATION R1227
J 0
(5175 25);
DISPLAY 1.021277 (5175 25);
DISPLAY INVISIBLE (5175 25);
FORCEPROP 2 LAST $SEC 1
J 0
(5175 25);
DISPLAY 0.680851 (5175 25);
PAINT MONO (5175 25);
DISPLAY INVISIBLE (5175 25);
FORCEPROP 2 LAST CDS_SEC 1
J 0
(5175 25);
DISPLAY 1.021277 (5175 25);
DISPLAY INVISIBLE (5175 25);
FORCEPROP 1 LAST PATH I56
J 0
(4825 -50);
DISPLAY 0.978723 (4825 -50);
PAINT WHITE (4825 -50);
DISPLAY INVISIBLE (4825 -50);
FORCEADD QUANTA_TITLE_BLOCK_C..1
(7500 -4725);
FORCEPROP 0 LAST CDS_CON_LAST_MODIFIED Fri Aug 25 14:00:26 2023
J 0
(5615 -4710);
PAINT MONO (5615 -4710);
DISPLAY INVISIBLE (5615 -4710);
FORCEPROP 2 LAST CUSTOM_TXT_CDS <XR_PAGE_TITLE>
J 0
(-390 525);
DISPLAY 0.638298 (-390 525);
PAINT PINK (-390 525);
DISPLAY INVISIBLE (-390 525);
FORCEPROP 2 LAST CUSTOM_TXT_CDS <CON_PAGE_NUM> OF <CON_TOTAL_PAGES>
J 0
(7050 -4700);
DISPLAY 0.978723 (7050 -4700);
FORCEPROP 2 LAST CUSTOM_TXT_CDS <Q_REV>
J 0
(7316 -4622);
DISPLAY 1.212766 (7316 -4622);
FORCEPROP 2 LAST CUSTOM_TXT_CDS <CON_LAST_MODIFIED>
J 0
(5625 -4700);
DISPLAY 0.978723 (5625 -4700);
FORCEPROP 2 LAST CUSTOM_TXT_CDS <Q_PROJ>
J 0
(5118 -4623);
DISPLAY 1.212766 (5118 -4623);
FORCEPROP 2 LAST CUSTOM_TXT_CDS <NAME_1>
J 0
(4325 -4550);
FORCEPROP 2 LAST CUSTOM_TXT_CDS <NAME_2>
J 0
(4325 -4675);
FORCEPROP 2 LAST CUSTOM_TXT_CDS <Q_NUMBER>
J 0
(6097 -4622);
DISPLAY 1.212766 (6097 -4622);
FORCEPROP 1 LAST Q_TITLE SPR CPU0 IBL/S3M SERIAL RESISTORS
J 0
(-1866 -4699);
DISPLAY 1.957447 (-1866 -4699);
PAINT GREEN (-1866 -4699);
FORCEPROP 1 LAST Q_DEPT 
J 1
(3737 -4676);
DISPLAY 1.957447 (3737 -4676);
PAINT GREEN (3737 -4676);
FORCEPROP 2 LAST CDS_LIB pure_quanta
J 0
(7500 -4725);
PAINT MONO (7500 -4725);
DISPLAY INVISIBLE (7500 -4725);
FORCEPROP 1 LAST CDS_LMAN_SYM_OUTLINE -9475,6775,100,-125
J 0
(7500 -4725);
DISPLAY 0.468085 (7500 -4725);
PAINT GREEN (7500 -4725);
DISPLAY INVISIBLE (7500 -4725);
FORCEPROP 2 LAST PAGE_BORDER TRUE
J 0
(-390 525);
DISPLAY 0.638298 (-390 525);
PAINT PINK (-390 525);
DISPLAY INVISIBLE (-390 525);
FORCEPROP 2 LAST CDS_XR_PAGE_TITLE CR-43 : @S9S_MB_2U_LIB.S9S_MB_2U(SCH_1):PAGE43
J 0
(-390 525);
DISPLAY 0.638298 (-390 525);
PAINT PINK (-390 525);
DISPLAY INVISIBLE (-390 525);
FORCEPROP 1 LAST COMMENT_BODY TRUE
J 0
(7512 -4738);
DISPLAY 0.978723 (7512 -4738);
PAINT GREEN (7512 -4738);
DISPLAY INVISIBLE (7512 -4738);
WIRE 16 -1 (1275 -2550)(1275 -2125);
WIRE 16 -1 (5700 -200)(5700 -325);
WIRE 16 -1 (5700 50)(5700 -200);
WIRE 16 -1 (5700 -200)(4975 -200);
WIRE 16 -1 (575 -1875)(1275 -1875);
WIRE 16 -1 (1275 -1875)(1275 -2125);
WIRE 16 -1 (575 -2125)(1275 -2125);
WIRE 16 -1 (-825 -2125)(375 -2125);
FORCEPROP 2 LAST SIG_NAME PWRGD_PLT_AUX_CPU1_LVT3
J 0
(-691 -2116);
DISPLAY 0.680851 (-691 -2116);
PAINT WHITE (-691 -2116);
WIRE 16 -1 (-825 -1875)(375 -1875);
FORCEPROP 2 LAST SIG_NAME PWRGD_PLT_AUX_CPU0_LVT3
J 0
(-691 -1866);
DISPLAY 0.680851 (-691 -1866);
PAINT WHITE (-691 -1866);
WIRE 16 -1 (4975 50)(5700 50);
WIRE 16 -1 (-825 800)(325 800);
FORCEPROP 2 LAST SIG_NAME PWRGD_PLT_AUX_CPU0_LVT3_R
J 0
(-716 809);
DISPLAY 0.680851 (-716 809);
PAINT WHITE (-716 809);
WIRE 16 -1 (2075 800)(525 800);
FORCEPROP 2 LAST SIG_NAME PWRGD_PLT_AUX_CPU0_LVT3
J 0
(1084 809);
DISPLAY 0.680851 (1084 809);
PAINT WHITE (1084 809);
WIRE 16 -1 (-825 550)(325 550);
FORCEPROP 2 LAST SIG_NAME PWRGD_PLT_AUX_CPU1_LVT3_R
J 0
(-716 559);
DISPLAY 0.680851 (-716 559);
PAINT WHITE (-716 559);
WIRE 16 -1 (2075 550)(525 550);
FORCEPROP 2 LAST SIG_NAME PWRGD_PLT_AUX_CPU1_LVT3
J 0
(1084 559);
DISPLAY 0.680851 (1084 559);
PAINT WHITE (1084 559);
WIRE 16 -1 (3625 -200)(4775 -200);
FORCEPROP 2 LAST SIG_NAME PD_JTAG_CPU1_PLD_TCK
J 0
(3734 -191);
DISPLAY 0.680851 (3734 -191);
PAINT WHITE (3734 -191);
WIRE 16 -1 (3625 50)(4775 50);
FORCEPROP 2 LAST SIG_NAME PD_JTAG_CPU0_PLD_TCK
J 0
(3734 59);
DISPLAY 0.680851 (3734 59);
PAINT WHITE (3734 59);
DOT 1 (1275 -2125);
DOT 1 (5700 -200);
QUIT
